# S9S_MB_2U (Grand Teton) — schematic netlist excerpt (pin names and nets, part order shuffled) for the footprints in the layout excerpt that follows; sources: Cadence DE-HDL packaged netlist, KiCad conversion of 03242023_DA0F0TMBIJ0_F0T_Motherboard_J_brd_V01_OCP.brd

J18  SCONN288_ADR50017P087CC  SCONN288_ADR50017-P087CC IO  pkg DDR288S_1-1VXB  page 99
  VIN_BULK0  = P12V_S3_AUX_CPU1_NVDIMM
  RFU0  = TP_CHA_CPU1_DIMM2_FRU_0
  VIN_MGMT  = P3V3_AUX
  HSCL  = I3C_SPD_DDRABCD_CPU1_LVC1_SCL_1
  HSDA  = I3C_SPD_DDRABCD_CPU1_LVC1_SDA
  VSS0  = GND
  DQ0_A  = M_A_CPU1_SA_DQ<0>
  VSS1  = GND
  DQ1_A  = M_A_CPU1_SA_DQ<1>
  VSS2  = GND
  DQS0_A_T  = M_A_CPU1_SA_DQS_DP<0>
  DQS0_A_C  = M_A_CPU1_SA_DQS_DN<0>
  VSS3  = GND
  DQ4_A  = M_A_CPU1_SA_DQ<4>
  VSS4  = GND
  DQ5_A  = M_A_CPU1_SA_DQ<5>
  VSS5  = GND
  DQ8_A  = M_A_CPU1_SA_DQ<8>
  VSS6  = GND
  DQ9_A  = M_A_CPU1_SA_DQ<9>
  VSS7  = GND
  DQS1_A_T  = M_A_CPU1_SA_DQS_DP<1>
  DQS1_A_C  = M_A_CPU1_SA_DQS_DN<1>
  VSS8  = GND
  DQ12_A  = M_A_CPU1_SA_DQ<12>
  VSS9  = GND
  DQ13_A  = M_A_CPU1_SA_DQ<13>
  VSS10  = GND
  DQ16_A  = M_A_CPU1_SA_DQ<16>
  VSS11  = GND
  DQ17_A  = M_A_CPU1_SA_DQ<17>
  VSS12  = GND
  DQS2_A_T  = M_A_CPU1_SA_DQS_DP<2>
  DQS2_A_C  = M_A_CPU1_SA_DQS_DN<2>
  VSS13  = GND
  DQ20_A  = M_A_CPU1_SA_DQ<20>
  VSS14  = GND
  DQ21_A  = M_A_CPU1_SA_DQ<21>
  VSS15  = GND
  DQ24_A  = M_A_CPU1_SA_DQ<24>
  VSS16  = GND
  DQ25_A  = M_A_CPU1_SA_DQ<25>
  VSS17  = GND
  DQS3_A_T  = M_A_CPU1_SA_DQS_DP<3>
  DQS3_A_C  = M_A_CPU1_SA_DQS_DN<3>
  VSS18  = GND
  DQ28_A  = M_A_CPU1_SA_DQ<28>
  VSS19  = GND
  DQ29_A  = M_A_CPU1_SA_DQ<29>
  VSS20  = GND
  CB0_A  = M_A_CPU1_SA_CB<0>
  VSS21  = GND
  CB1_A  = M_A_CPU1_SA_CB<1>
  VSS22  = GND
  DQS4_A_T  = M_A_CPU1_SA_DQS_DP<4>
  DQS4_A_C  = M_A_CPU1_SA_DQS_DN<4>
  VSS23  = GND
  CB4_A  = M_A_CPU1_SA_CB<4>
  VSS24  = GND
  CB5_A  = M_A_CPU1_SA_CB<5>
  VSS25  = GND
  ALERT_N  = M_A_CPU1_ALERT_N
  VSS26  = GND
  CS0_A_N  = M_A_CPU1_SA_CS_N<2>
  VSS27  = GND
  CA0_A  = M_A_CPU1_SA_CA<0>
  VSS28  = GND
  CA2_A  = M_A_CPU1_SA_CA<2>
  VSS29  = GND
  CA4_A  = M_A_CPU1_SA_CA<4>
  VSS30  = GND
  CA6_A  = M_A_CPU1_SA_CA<6>
  VSS31  = GND
  PAR_A  = M_A_CPU1_SA_PAR
  VSS32  = GND
  CA0_B  = M_A_CPU1_SB_CA<0>
  VSS33  = GND
  CA2_B  = M_A_CPU1_SB_CA<2>
  VSS34  = GND
  CA4_B  = M_A_CPU1_SB_CA<4>
  VSS35  = GND
  CA6_B  = M_A_CPU1_SB_CA<6>
  VSS36  = GND
  CS0_B_N  = M_A_CPU1_SB_CS_N<2>
  VSS37  = GND
  \lbd||rsp_a_n\  = M_A_CPU1_SA_RSP<1>
  \lbs||rsp_b_n\  = M_A_CPU1_SB_RSP<1>
  VSS38  = GND
  CB4_B  = M_A_CPU1_SB_CB<4>
  VSS39  = GND
  CB5_B  = M_A_CPU1_SB_CB<5>
  VSS40  = GND
  \dqs9_b_t||tdqs9_b_t||dbi4_b_n\  = M_A_CPU1_SB_DQS_DP<9>
  \dqs9_b_c||tdqs9_b_c\  = M_A_CPU1_SB_DQS_DN<9>
  VSS41  = GND
  CB0_B  = M_A_CPU1_SB_CB<0>
  VSS42  = GND
  CB1_B  = M_A_CPU1_SB_CB<1>
  VSS43  = GND
  DQ0_B  = M_A_CPU1_SB_DQ<0>
  VSS44  = GND
  DQ1_B  = M_A_CPU1_SB_DQ<1>
  VSS45  = GND
  DQS0_B_T  = M_A_CPU1_SB_DQS_DP<0>
  DQS0_B_C  = M_A_CPU1_SB_DQS_DN<0>
  VSS46  = GND
  DQ4_B  = M_A_CPU1_SB_DQ<4>
  VSS47  = GND
  DQ5_B  = M_A_CPU1_SB_DQ<5>
  VSS48  = GND
  DQ8_B  = M_A_CPU1_SB_DQ<8>
  VSS49  = GND
  DQ9_B  = M_A_CPU1_SB_DQ<9>
  VSS50  = GND
  DQS1_B_T  = M_A_CPU1_SB_DQS_DP<1>
  DQS1_B_C  = M_A_CPU1_SB_DQS_DN<1>
  VSS51  = GND
  DQ12_B  = M_A_CPU1_SB_DQ<12>
  VSS52  = GND
  DQ13_B  = M_A_CPU1_SB_DQ<13>
  VSS53  = GND
  DQ16_B  = M_A_CPU1_SB_DQ<16>
  VSS54  = GND
  DQ17_B  = M_A_CPU1_SB_DQ<17>
  VSS55  = GND
  DQS2_B_T  = M_A_CPU1_SB_DQS_DP<2>
  DQS2_B_C  = M_A_CPU1_SB_DQS_DN<2>
  VSS56  = GND
  DQ20_B  = M_A_CPU1_SB_DQ<20>
  VSS57  = GND
  DQ21_B  = M_A_CPU1_SB_DQ<21>
  VSS58  = GND
  DQ24_B  = M_A_CPU1_SB_DQ<24>
  VSS59  = GND
  DQ25_B  = M_A_CPU1_SB_DQ<25>
  VSS60  = GND
  DQS3_B_T  = M_A_CPU1_SB_DQS_DP<3>
  DQS3_B_C  = M_A_CPU1_SB_DQS_DN<3>
  VSS61  = GND
  DQ28_B  = M_A_CPU1_SB_DQ<28>
  VSS62  = GND
  DQ29_B  = M_A_CPU1_SB_DQ<29>
  VSS63  = GND
  RFU1  = TP_CHA_CPU1_DIMM2_FRU_1
  VIN_BULK1  = P12V_S3_AUX_CPU1_NVDIMM
  VIN_BULK2  = P12V_S3_AUX_CPU1_NVDIMM
  \pwr_good||fail_n\  = PWRGD_CHA_CPU1_DIMM2
  HSA  = PD_CHA_CPU1_DIMM2_SAA
  RFU2  = TP_CHA_CPU1_DIMM2_FRU_2
  RFU3  = TP_CHA_CPU1_DIMM2_FRU_3
  VSS64  = GND
  DQ2_A  = M_A_CPU1_SA_DQ<2>
  VSS65  = GND
  DQ3_A  = M_A_CPU1_SA_DQ<3>
  VSS66  = GND
  \dqs5_a_c||tdqs5_a_c||dqs5_a_t||tdqs5_a_t\  = M_A_CPU1_SA_DQS_DN<5>
  \dqs5_a_t||tdqs5_a_t\  = M_A_CPU1_SA_DQS_DP<5>
  VSS67  = GND
  DQ6_A  = M_A_CPU1_SA_DQ<6>
  VSS68  = GND
  DQ7_A  = M_A_CPU1_SA_DQ<7>
  VSS69  = GND
  DQ10_A  = M_A_CPU1_SA_DQ<10>
  VSS70  = GND
  DQ11_A  = M_A_CPU1_SA_DQ<11>
  VSS71  = GND
  \dqs6_a_c||tdqs6_a_c||dqs6_a_t||tdqs6_a_t\  = M_A_CPU1_SA_DQS_DN<6>
  \dqs6_a_t||tdqs6_a_t\  = M_A_CPU1_SA_DQS_DP<6>
  VSS72  = GND
  DQ14_A  = M_A_CPU1_SA_DQ<14>
  VSS73  = GND
  DQ15_A  = M_A_CPU1_SA_DQ<15>
  VSS74  = GND
  DQ18_A  = M_A_CPU1_SA_DQ<18>
  VSS75  = GND
  DQ19_A  = M_A_CPU1_SA_DQ<19>
  VSS76  = GND
  \dqs7_a_c||tdqs7_a_c\  = M_A_CPU1_SA_DQS_DN<7>
  \dqs7_a_t||tdqs7_a_t\  = M_A_CPU1_SA_DQS_DP<7>
  VSS77  = GND
  DQ22_A  = M_A_CPU1_SA_DQ<22>
  VSS78  = GND
  DQ23_A  = M_A_CPU1_SA_DQ<23>
  VSS79  = GND
  DQ26_A  = M_A_CPU1_SA_DQ<26>
  VSS80  = GND
  DQ27_A  = M_A_CPU1_SA_DQ<27>
  VSS81  = GND
  \dqs8_a_c||tdqs8_a_c\  = M_A_CPU1_SA_DQS_DN<8>
  \dqs8_a_t||tdqs8_a_t\  = M_A_CPU1_SA_DQS_DP<8>
  VSS82  = GND
  DQ30_A  = M_A_CPU1_SA_DQ<30>
  VSS83  = GND
  DQ31_A  = M_A_CPU1_SA_DQ<31>
  VSS84  = GND
  CB2_A  = M_A_CPU1_SA_CB<2>
  VSS85  = GND
  CB3_A  = M_A_CPU1_SA_CB<3>
  VSS86  = GND
  \dqs9_a_c||tdqs9_a_c\  = M_A_CPU1_SA_DQS_DN<9>
  \dqs9_a_t||tdqs9_a_t\  = M_A_CPU1_SA_DQS_DP<9>
  VSS87  = GND
  CB6_A  = M_A_CPU1_SA_CB<6>
  VSS88  = GND
  CB7_A  = M_A_CPU1_SA_CB<7>
  VSS89  = GND
  RESET_N  = RST_M_AB_CPU1_FPGA_N
  VSS90  = GND
  CS1_A_N  = M_A_CPU1_SA_CS_N<3>
  VSS91  = GND
  CA1_A  = M_A_CPU1_SA_CA<1>
  VSS92  = GND
  CA3_A  = M_A_CPU1_SA_CA<3>
  VSS93  = GND
  CA5_A  = M_A_CPU1_SA_CA<5>
  VSS94  = GND
  CK_T  = M_A_CPU1_CLK_DP<1>
  CK_C  = M_A_CPU1_CLK_DN<1>
  VSS95  = GND
  RFU4  = TP_CHA_CPU1_DIMM2_FRU_4
  CA1_B  = M_A_CPU1_SB_CA<1>
  VSS96  = GND
  CA3_B  = M_A_CPU1_SB_CA<3>
  VSS97  = GND
  CA5_B  = M_A_CPU1_SB_CA<5>
  VSS98  = GND
  PAR_B  = M_A_CPU1_SB_PAR
  VSS99  = GND
  CS1_B_N  = M_A_CPU1_SB_CS_N<3>
  VSS100  = GND
  RFU5  = TP_CHA_CPU1_DIMM2_FRU_5
  RFU6  = TP_CHA_CPU1_DIMM2_FRU_6
  VSS101  = GND
  CB6_B  = M_A_CPU1_SB_CB<6>
  VSS102  = GND
  CB7_B  = M_A_CPU1_SB_CB<7>
  VSS103  = GND
  DQS4_B_C  = M_A_CPU1_SB_DQS_DN<4>
  DQS4_B_T  = M_A_CPU1_SB_DQS_DP<4>
  VSS104  = GND
  CB2_B  = M_A_CPU1_SB_CB<2>
  VSS105  = GND
  CB3_B  = M_A_CPU1_SB_CB<3>
  VSS106  = GND
  DQ2_B  = M_A_CPU1_SB_DQ<2>
  VSS107  = GND
  DQ3_B  = M_A_CPU1_SB_DQ<3>
  VSS108  = GND
  \dqs5_b_c||tdqs5_b_c\  = M_A_CPU1_SB_DQS_DN<5>
  \dqs5_b_t||tdqs5_b_t\  = M_A_CPU1_SB_DQS_DP<5>
  VSS109  = GND
  DQ6_B  = M_A_CPU1_SB_DQ<6>
  VSS110  = GND
  DQ7_B  = M_A_CPU1_SB_DQ<7>
  VSS111  = GND
  DQ10_B  = M_A_CPU1_SB_DQ<10>
  VSS112  = GND
  DQ11_B  = M_A_CPU1_SB_DQ<11>
  VSS113  = GND
  \dqs6_b_c||tdqs6_b_c\  = M_A_CPU1_SB_DQS_DN<6>
  \dqs6_b_t||tdqs6_b_t\  = M_A_CPU1_SB_DQS_DP<6>
  VSS114  = GND
  DQ14_B  = M_A_CPU1_SB_DQ<14>
  VSS115  = GND
  DQ15_B  = M_A_CPU1_SB_DQ<15>
  VSS116  = GND
  DQ18_B  = M_A_CPU1_SB_DQ<18>
  VSS117  = GND
  DQ19_B  = M_A_CPU1_SB_DQ<19>
  VSS118  = GND
  \dqs7_b_c||tdqs7_b_c\  = M_A_CPU1_SB_DQS_DN<7>
  \dqs7_b_t||tdqs7_b_t\  = M_A_CPU1_SB_DQS_DP<7>
  VSS119  = GND
  DQ22_B  = M_A_CPU1_SB_DQ<22>
  VSS120  = GND
  DQ23_B  = M_A_CPU1_SB_DQ<23>
  VSS121  = GND
  DQ26_B  = M_A_CPU1_SB_DQ<26>
  VSS122  = GND
  DQ27_B  = M_A_CPU1_SB_DQ<27>
  VSS123  = GND
  \dqs8_b_c||tdqs8_b_c\  = M_A_CPU1_SB_DQS_DN<8>
  \dqs8_b_t||tdqs8_b_t\  = M_A_CPU1_SB_DQS_DP<8>
  VSS124  = GND
  DQ30_B  = M_A_CPU1_SB_DQ<30>
  VSS125  = GND
  DQ31_B  = M_A_CPU1_SB_DQ<31>
  VSS126  = GND
  G1  = GND
  G2  = GND
  G3  = GND

(kicad_pcb
	(version 20260206)
	(generator "pcbnew")
	(generator_version "10.0")
	(general
		(thickness 1.6)
		(legacy_teardrops no)
	)
	(paper "A4")
	(title_block
		(title "03242023_DA0F0TMBIJ0_F0T_Motherboard_J_brd_V01_OCP.brd")
		(comment 1 "Grand Teton / footprint 3819 of 6105 (J18), pads 46-91 of 291")
	)
	(layers
		(0 "F.Cu" signal "TOP")
		(4 "In1.Cu" signal "GND")
		(6 "In2.Cu" signal "IN1")
		(8 "In3.Cu" signal "GND1")
		(10 "In4.Cu" signal "IN2")
		(12 "In5.Cu" signal "GND2")
		(14 "In6.Cu" signal "IN3")
		(16 "In7.Cu" signal "GND3")
		(18 "In8.Cu" signal "VCC")
		(20 "In9.Cu" signal "VCC1")
		(22 "In10.Cu" signal "GND4")
		(24 "In11.Cu" signal "IN4")
		(26 "In12.Cu" signal "GND5")
		(28 "In13.Cu" signal "IN5")
		(30 "In14.Cu" signal "GND6")
		(32 "In15.Cu" signal "IN6")
		(34 "In16.Cu" signal "GND7")
		(2 "B.Cu" signal "BOTTOM")
		(9 "F.Adhes" user "F.Adhesive")
		(11 "B.Adhes" user "B.Adhesive")
		(13 "F.Paste" user "Package Geometry/Pastemask Top")
		(15 "B.Paste" user "Package Geometry/Pastemask Bottom")
		(5 "F.SilkS" user "Ref Des/Silkscreen Top")
		(7 "B.SilkS" user "Ref Des/Silkscreen Bottom")
		(1 "F.Mask" user "Board Geometry/Soldermask Top")
		(3 "B.Mask" user "Board Geometry/Soldermask Bottom")
		(17 "Dwgs.User" user "User.Drawings")
		(19 "Cmts.User" user "User.Comments")
		(21 "Eco1.User" user "User.Eco1")
		(23 "Eco2.User" user "User.Eco2")
		(25 "Edge.Cuts" user "Board Geometry/Outline")
		(27 "Margin" user)
		(31 "F.CrtYd" user "Package Geometry/Place Bound Top")
		(29 "B.CrtYd" user "Package Geometry/Place Bound Bottom")
		(35 "F.Fab" user "Ref Des/Assembly Top")
		(33 "B.Fab" user "Ref Des/Assembly Bottom")
	)
	(footprint ""
		(layer "F.Cu")
		(at 62.99708 -258.091686)
		(property "Reference" "J18"
			(at -1.547622 -81.836514 0)
			(unlocked yes)
			(layer "F.SilkS")
			(effects
				(font
					(size 0.7874 0.5842)
					(thickness 0.1524)
				)
				(justify left)
			)
		)
		(property "Value" ""
			(at 0 0 0)
			(layer "F.Fab")
			(effects
				(font
					(size 1.27 1.27)
				)
			)
		)
		(duplicate_pad_numbers_are_jumpers no)
		(pad "46" smd rect
			(at -2.050034 -25.07488 270)
			(size 0.519938 1.4986)
			(layers "F.Cu" "F.Mask" "F.Paste")
			(net "GND")
		)
		(pad "47" smd rect
			(at -2.050034 -24.224996 270)
			(size 0.519938 1.4986)
			(layers "F.Cu" "F.Mask" "F.Paste")
			(net "M_A_CPU1_SA_DQ<28>")
		)
		(pad "48" smd rect
			(at -2.050034 -23.375112 270)
			(size 0.519938 1.4986)
			(layers "F.Cu" "F.Mask" "F.Paste")
			(net "GND")
		)
		(pad "49" smd rect
			(at -2.050034 -22.524974 270)
			(size 0.519938 1.4986)
			(layers "F.Cu" "F.Mask" "F.Paste")
			(net "M_A_CPU1_SA_DQ<29>")
		)
		(pad "50" smd rect
			(at -2.050034 -21.67509 270)
			(size 0.519938 1.4986)
			(layers "F.Cu" "F.Mask" "F.Paste")
			(net "GND")
		)
		(pad "51" smd rect
			(at -2.050034 -20.824952 270)
			(size 0.519938 1.4986)
			(layers "F.Cu" "F.Mask" "F.Paste")
			(net "M_A_CPU1_SA_CB<0>")
		)
		(pad "52" smd rect
			(at -2.050034 -19.975068 270)
			(size 0.519938 1.4986)
			(layers "F.Cu" "F.Mask" "F.Paste")
			(net "GND")
		)
		(pad "53" smd rect
			(at -2.050034 -19.12493 270)
			(size 0.519938 1.4986)
			(layers "F.Cu" "F.Mask" "F.Paste")
			(net "M_A_CPU1_SA_CB<1>")
		)
		(pad "54" smd rect
			(at -2.050034 -18.275046 270)
			(size 0.519938 1.4986)
			(layers "F.Cu" "F.Mask" "F.Paste")
			(net "GND")
		)
		(pad "55" smd rect
			(at -2.050034 -17.424908 270)
			(size 0.519938 1.4986)
			(layers "F.Cu" "F.Mask" "F.Paste")
			(net "M_A_CPU1_SA_DQS_DP<4>")
		)
		(pad "56" smd rect
			(at -2.050034 -16.575024 270)
			(size 0.519938 1.4986)
			(layers "F.Cu" "F.Mask" "F.Paste")
			(net "M_A_CPU1_SA_DQS_DN<4>")
		)
		(pad "57" smd rect
			(at -2.050034 -15.724886 270)
			(size 0.519938 1.4986)
			(layers "F.Cu" "F.Mask" "F.Paste")
			(net "GND")
		)
		(pad "58" smd rect
			(at -2.050034 -14.875002 270)
			(size 0.519938 1.4986)
			(layers "F.Cu" "F.Mask" "F.Paste")
			(net "M_A_CPU1_SA_CB<4>")
		)
		(pad "59" smd rect
			(at -2.050034 -14.025118 270)
			(size 0.519938 1.4986)
			(layers "F.Cu" "F.Mask" "F.Paste")
			(net "GND")
		)
		(pad "60" smd rect
			(at -2.050034 -13.17498 270)
			(size 0.519938 1.4986)
			(layers "F.Cu" "F.Mask" "F.Paste")
			(net "M_A_CPU1_SA_CB<5>")
		)
		(pad "61" smd rect
			(at -2.050034 -12.325096 270)
			(size 0.519938 1.4986)
			(layers "F.Cu" "F.Mask" "F.Paste")
			(net "GND")
		)
		(pad "62" smd rect
			(at -2.050034 -11.474958 270)
			(size 0.519938 1.4986)
			(layers "F.Cu" "F.Mask" "F.Paste")
			(net "M_A_CPU1_ALERT_N")
		)
		(pad "63" smd rect
			(at -2.050034 -10.625074 270)
			(size 0.519938 1.4986)
			(layers "F.Cu" "F.Mask" "F.Paste")
			(net "GND")
		)
		(pad "64" smd rect
			(at -2.050034 -9.774936 270)
			(size 0.519938 1.4986)
			(layers "F.Cu" "F.Mask" "F.Paste")
			(net "M_A_CPU1_SA_CS_N<2>")
		)
		(pad "65" smd rect
			(at -2.050034 -8.925052 270)
			(size 0.519938 1.4986)
			(layers "F.Cu" "F.Mask" "F.Paste")
			(net "GND")
		)
		(pad "66" smd rect
			(at -2.050034 -8.074914 270)
			(size 0.519938 1.4986)
			(layers "F.Cu" "F.Mask" "F.Paste")
			(net "M_A_CPU1_SA_CA<0>")
		)
		(pad "67" smd rect
			(at -2.050034 -7.22503 270)
			(size 0.519938 1.4986)
			(layers "F.Cu" "F.Mask" "F.Paste")
			(net "GND")
		)
		(pad "68" smd rect
			(at -2.050034 -6.374892 270)
			(size 0.519938 1.4986)
			(layers "F.Cu" "F.Mask" "F.Paste")
			(net "M_A_CPU1_SA_CA<2>")
		)
		(pad "69" smd rect
			(at -2.050034 -5.525008 270)
			(size 0.519938 1.4986)
			(layers "F.Cu" "F.Mask" "F.Paste")
			(net "GND")
		)
		(pad "70" smd rect
			(at -2.050034 -4.675124 270)
			(size 0.519938 1.4986)
			(layers "F.Cu" "F.Mask" "F.Paste")
			(net "M_A_CPU1_SA_CA<4>")
		)
		(pad "71" smd rect
			(at -2.050034 -3.824986 270)
			(size 0.519938 1.4986)
			(layers "F.Cu" "F.Mask" "F.Paste")
			(net "GND")
		)
		(pad "72" smd rect
			(at -2.050034 -2.975102 270)
			(size 0.519938 1.4986)
			(layers "F.Cu" "F.Mask" "F.Paste")
			(net "M_A_CPU1_SA_CA<6>")
		)
		(pad "73" smd rect
			(at -2.050034 -2.124964 270)
			(size 0.519938 1.4986)
			(layers "F.Cu" "F.Mask" "F.Paste")
			(net "GND")
		)
		(pad "74" smd rect
			(at -2.050034 -1.27508 270)
			(size 0.519938 1.4986)
			(layers "F.Cu" "F.Mask" "F.Paste")
			(net "M_A_CPU1_SA_PAR")
		)
		(pad "75" smd rect
			(at -2.050034 -0.424942 270)
			(size 0.519938 1.4986)
			(layers "F.Cu" "F.Mask" "F.Paste")
			(net "GND")
		)
		(pad "76" smd rect
			(at -2.050034 5.525008 270)
			(size 0.519938 1.4986)
			(layers "F.Cu" "F.Mask" "F.Paste")
			(net "M_A_CPU1_SB_CA<0>")
		)
		(pad "77" smd rect
			(at -2.050034 6.374892 270)
			(size 0.519938 1.4986)
			(layers "F.Cu" "F.Mask" "F.Paste")
			(net "GND")
		)
		(pad "78" smd rect
			(at -2.050034 7.22503 270)
			(size 0.519938 1.4986)
			(layers "F.Cu" "F.Mask" "F.Paste")
			(net "M_A_CPU1_SB_CA<2>")
		)
		(pad "79" smd rect
			(at -2.050034 8.074914 270)
			(size 0.519938 1.4986)
			(layers "F.Cu" "F.Mask" "F.Paste")
			(net "GND")
		)
		(pad "80" smd rect
			(at -2.050034 8.925052 270)
			(size 0.519938 1.4986)
			(layers "F.Cu" "F.Mask" "F.Paste")
			(net "M_A_CPU1_SB_CA<4>")
		)
		(pad "81" smd rect
			(at -2.050034 9.774936 270)
			(size 0.519938 1.4986)
			(layers "F.Cu" "F.Mask" "F.Paste")
			(net "GND")
		)
		(pad "82" smd rect
			(at -2.050034 10.625074 270)
			(size 0.519938 1.4986)
			(layers "F.Cu" "F.Mask" "F.Paste")
			(net "M_A_CPU1_SB_CA<6>")
		)
		(pad "83" smd rect
			(at -2.050034 11.474958 270)
			(size 0.519938 1.4986)
			(layers "F.Cu" "F.Mask" "F.Paste")
			(net "GND")
		)
		(pad "84" smd rect
			(at -2.050034 12.325096 270)
			(size 0.519938 1.4986)
			(layers "F.Cu" "F.Mask" "F.Paste")
			(net "M_A_CPU1_SB_CS_N<2>")
		)
		(pad "85" smd rect
			(at -2.050034 13.17498 270)
			(size 0.519938 1.4986)
			(layers "F.Cu" "F.Mask" "F.Paste")
			(net "GND")
		)
		(pad "86" smd rect
			(at -2.050034 14.025118 270)
			(size 0.519938 1.4986)
			(layers "F.Cu" "F.Mask" "F.Paste")
			(net "M_A_CPU1_SA_RSP<1>")
		)
		(pad "87" smd rect
			(at -2.050034 14.875002 270)
			(size 0.519938 1.4986)
			(layers "F.Cu" "F.Mask" "F.Paste")
			(net "M_A_CPU1_SB_RSP<1>")
		)
		(pad "88" smd rect
			(at -2.050034 15.724886 270)
			(size 0.519938 1.4986)
			(layers "F.Cu" "F.Mask" "F.Paste")
			(net "GND")
		)
		(pad "89" smd rect
			(at -2.050034 16.575024 270)
			(size 0.519938 1.4986)
			(layers "F.Cu" "F.Mask" "F.Paste")
			(net "M_A_CPU1_SB_CB<4>")
		)
		(pad "90" smd rect
			(at -2.050034 17.424908 270)
			(size 0.519938 1.4986)
			(layers "F.Cu" "F.Mask" "F.Paste")
			(net "GND")
		)
		(pad "91" smd rect
			(at -2.050034 18.275046 270)
			(size 0.519938 1.4986)
			(layers "F.Cu" "F.Mask" "F.Paste")
			(net "M_A_CPU1_SB_CB<5>")
		)
	)
)
